FILE_TYPE = MULTI_PHYS_TABLE;
PART 'CONN9_H51826001'
{==================================================================================================================================================================================}
:PACK_TYPE | MATERIAL | PART_NUMBER    = EnvComp | PART_NUMBER   | JEDEC_TYPE            | CLASS | DESCRIPTION                                              | COMPONENT_TYPE | HEIGHT     | LEAD_LENGTH   | SPEED_URL | Status |RPL| AML | Bus_Unit | Days ;
{==================================================================================================================================================================================}
'IO'       | 'CONN'   | 'H51826-001'(!)= ''      | 'H51826-001'  | 'CONN9_H51826001'     | 'IO'  | '(GENERIC IO USE SYM_1)CONN,I/O,9P,USB,FLG,MIXED,062ST'  | 'THMT'         | '0.553 IN' | '0.096'       | 'http://speed.intel.com:8081/speed/module/pdm/item/pdm_item_detail_direct.asp?item_cde=H51826-001&item_rev=01&url_param=unused' | '' | '' | '' | '' | '' 
'IO'       | 'EMPTY'  | 'H51826-001'(!)= ''      | 'H51826-001'  | 'CONN9_H51826001'     | 'IO'  | '(GENERIC IO USE SYM_1)CONN,I/O,9P,USB,FLG,MIXED,062ST'  | 'THMT'         | '0.553 IN' | '0.096'       | 'http://speed.intel.com:8081/speed/module/pdm/item/pdm_item_detail_direct.asp?item_cde=H51826-001&item_rev=01&url_param=unused' | '' | '' | '' | '' | '' 
'THMT'     | 'CONN'   | 'H51826-001'(!)= ''      | 'H51826-001'  | 'CONN9_H51826001'     | 'IO'  | '(USB 3.0 USE SYM_2)   CONN,I/O,9P,USB,FLG,MIXED,062ST'  | 'THMT'         | '0.553 IN' | '0.096'       | 'http://speed.intel.com:8081/speed/module/pdm/item/pdm_item_detail_direct.asp?item_cde=H51826-001&item_rev=01&url_param=unused' | '' | '' | '' | '' | '' 
'THMT'     | 'EMPTY'  | 'H51826-001'(!)= ''      | 'H51826-001'  | 'CONN9_H51826001'     | 'IO'  | '(USB 3.0 USE SYM_2)   CONN,I/O,9P,USB,FLG,MIXED,062ST'  | 'THMT'         | '0.553 IN' | '0.096'       | 'http://speed.intel.com:8081/speed/module/pdm/item/pdm_item_detail_direct.asp?item_cde=H51826-001&item_rev=01&url_param=unused' | '' | '' | '' | '' | '' 
'PIP1'     | 'CONN'   | 'H51826-001'(!)= ''      | 'H51826-001'  | 'CONN9_H51826001_PIP' | 'IO'  | '(GENERIC IO USE SYM_1)CONN,I/O,9P,USB,FLG,MIXED,062ST'  | 'THMT'         | '0.553 IN' | '0.096'       | 'http://speed.intel.com:8081/speed/module/pdm/item/pdm_item_detail_direct.asp?item_cde=H51826-001&item_rev=01&url_param=unused' | '' | '' | '' | '' | '' 
'PIP1'     | 'EMPTY'  | 'H51826-001'(!)= ''      | 'H51826-001'  | 'CONN9_H51826001_PIP' | 'IO'  | '(GENERIC IO USE SYM_1)CONN,I/O,9P,USB,FLG,MIXED,062ST'  | 'THMT'         | '0.553 IN' | '0.096'       | 'http://speed.intel.com:8081/speed/module/pdm/item/pdm_item_detail_direct.asp?item_cde=H51826-001&item_rev=01&url_param=unused' | '' | '' | '' | '' | '' 
'PIP2'     | 'CONN'   | 'H51826-001'(!)= ''      | 'H51826-001'  | 'CONN9_H51826001_PIP' | 'IO'  | '(USB 3.0 USE SYM_2)   CONN,I/O,9P,USB,FLG,MIXED,062ST'  | 'THMT'         | '0.553 IN' | '0.096'       | 'http://speed.intel.com:8081/speed/module/pdm/item/pdm_item_detail_direct.asp?item_cde=H51826-001&item_rev=01&url_param=unused' | '' | '' | '' | '' | '' 
'PIP2'     | 'EMPTY'  | 'H51826-001'(!)= ''      | 'H51826-001'  | 'CONN9_H51826001_PIP' | 'IO'  | '(USB 3.0 USE SYM_2)   CONN,I/O,9P,USB,FLG,MIXED,062ST'  | 'THMT'         | '0.553 IN' | '0.096'       | 'http://speed.intel.com:8081/speed/module/pdm/item/pdm_item_detail_direct.asp?item_cde=H51826-001&item_rev=01&url_param=unused' | '' | '' | '' | '' | '' 
END_PART
END.
